(kicad_pcb
	(version 20241229)
	(generator "pcbnew")
	(generator_version "9.0")
	(general
		(thickness 1.6)
		(legacy_teardrops no)
	)
	(paper "A4")
	(title_block
		(title "GMSL Deserializer")
		(date "2025-10-09")
		(rev "1.0.4")
		(company "Antmicro Ltd")
		(comment 1 "www.antmicro.com")
		(comment 9 "footprints 79-84 of 235")
	)
	(layers
		(0 "F.Cu" signal)
		(4 "In1.Cu" power)
		(6 "In2.Cu" power)
		(2 "B.Cu" signal)
		(9 "F.Adhes" user "F.Adhesive")
		(11 "B.Adhes" user "B.Adhesive")
		(13 "F.Paste" user)
		(15 "B.Paste" user)
		(5 "F.SilkS" user "F.Silkscreen")
		(7 "B.SilkS" user "B.Silkscreen")
		(1 "F.Mask" user)
		(3 "B.Mask" user)
		(17 "Dwgs.User" user "User.Drawings")
		(19 "Cmts.User" user "User.Comments")
		(21 "Eco1.User" user "User.Eco1")
		(23 "Eco2.User" user "User.Eco2")
		(25 "Edge.Cuts" user)
		(27 "Margin" user)
		(31 "F.CrtYd" user "F.Courtyard")
		(29 "B.CrtYd" user "B.Courtyard")
		(35 "F.Fab" user)
		(33 "B.Fab" user)
	)
	(footprint "antmicro-footprints:R_0402_1005Metric"
		(layer "F.Cu")
		(at 170.68 69.857)
		(descr "Resistor SMD 0402")
		(tags "resistor SMD 0402")
		(property "Reference" "R68"
			(at -3.140968 0.337135 0)
			(layer "F.SilkS")
			(effects
				(font
					(size 0.7 0.7)
					(thickness 0.15)
				)
				(justify left bottom)
			)
		)
		(property "Value" "R_100R_0402"
			(at -1.011843 1.772047 0)
			(layer "F.Fab")
			(effects
				(font
					(size 0.7 0.7)
					(thickness 0.15)
				)
				(justify left bottom)
			)
		)
		(property "Datasheet" "https://www.bourns.com/docs/product-datasheets/cr.pdf"
			(at 0 0 0)
			(layer "F.Fab")
			(hide yes)
			(effects
				(font
					(size 1.27 1.27)
					(thickness 0.15)
				)
			)
		)
		(property "Description" "SMD Chip Resistor, 100 ohm, ± 1%, 62.5 mW, 0402 [1005 Metric], Thick Film, General Purpose"
			(at 0 0 0)
			(layer "F.Fab")
			(hide yes)
			(effects
				(font
					(size 1.27 1.27)
					(thickness 0.15)
				)
			)
		)
		(property "Author" "Antmicro"
			(at 0 0 0)
			(layer "F.Fab")
			(hide yes)
			(effects
				(font
					(size 1 1)
					(thickness 0.15)
				)
			)
		)
		(property "License" "Apache-2.0"
			(at 0 0 0)
			(layer "F.Fab")
			(hide yes)
			(effects
				(font
					(size 1 1)
					(thickness 0.15)
				)
			)
		)
		(property "MPN" "CR0402-FX-1000GLF"
			(at 0 0 0)
			(layer "F.Fab")
			(hide yes)
			(effects
				(font
					(size 1 1)
					(thickness 0.15)
				)
			)
		)
		(property "Manufacturer" "Bourns"
			(at 0 0 0)
			(layer "F.Fab")
			(hide yes)
			(effects
				(font
					(size 1 1)
					(thickness 0.15)
				)
			)
		)
		(property "Tolerance" "1%"
			(at 0 0 0)
			(layer "F.Fab")
			(hide yes)
			(effects
				(font
					(size 1 1)
					(thickness 0.15)
				)
			)
		)
		(property "Val" "100R"
			(at 0 0 0)
			(layer "F.Fab")
			(hide yes)
			(effects
				(font
					(size 1 1)
					(thickness 0.15)
				)
			)
		)
		(sheetname "/Connectors/")
		(sheetfile "connectors.kicad_sch")
		(attr smd exclude_from_pos_files exclude_from_bom dnp)
		(fp_rect
			(start -0.925 -0.47)
			(end 0.925 0.47)
			(stroke
				(width 0.05)
				(type default)
			)
			(fill no)
			(layer "F.CrtYd")
		)
		(fp_rect
			(start -0.5 -0.25)
			(end 0.5 0.25)
			(stroke
				(width 0.15)
				(type solid)
			)
			(fill no)
			(layer "F.Fab")
		)
		(pad "1" smd roundrect
			(at -0.48 0)
			(size 0.59 0.64)
			(layers "F.Cu" "F.Mask" "F.Paste")
			(roundrect_rratio 0.25)
			(net 86 "/Connectors/MFP7")
			(pintype "passive")
		)
		(pad "2" smd roundrect
			(at 0.48 0)
			(size 0.59 0.64)
			(layers "F.Cu" "F.Mask" "F.Paste")
			(roundrect_rratio 0.25)
			(net 133 "Net-(U8-A_{1})")
			(pintype "passive")
		)
	)
	(footprint "antmicro-footprints:L_Coilcraft-1210POC"
		(layer "F.Cu")
		(at 124.968 56.642 90)
		(property "Reference" "L5"
			(at -0.635 -1.778 90)
			(layer "F.SilkS")
			(effects
				(font
					(size 0.7 0.7)
					(thickness 0.15)
				)
				(justify left bottom)
			)
		)
		(property "Value" "L_6u8_1A_Coilcraft-1210POC"
			(at 0 2.4 90)
			(layer "F.Fab")
			(effects
				(font
					(size 0.7 0.7)
					(thickness 0.15)
				)
				(justify left bottom)
			)
		)
		(property "Datasheet" "https://www.coilcraft.com/getmedia/5e8de018-68c5-4442-84ce-d5212c44660c/1210poc.pdf"
			(at 0 0 90)
			(layer "F.Fab")
			(hide yes)
			(effects
				(font
					(size 1.27 1.27)
					(thickness 0.15)
				)
			)
		)
		(property "Description" "Power Inductor (SMT), 6.8 µH, 9.2 A, Shielded, 12.8 A, XAL7070"
			(at 0 0 90)
			(layer "F.Fab")
			(hide yes)
			(effects
				(font
					(size 1.27 1.27)
					(thickness 0.15)
				)
			)
		)
		(property "Author" "Antmicro"
			(at 181.61 -68.326 0)
			(layer "F.Fab")
			(hide yes)
			(effects
				(font
					(size 1 1)
					(thickness 0.15)
				)
			)
		)
		(property "IMax" "1.36 A"
			(at 181.61 -68.326 0)
			(layer "F.Fab")
			(hide yes)
			(effects
				(font
					(size 1 1)
					(thickness 0.15)
				)
			)
		)
		(property "ISat" "1 A"
			(at 181.61 -68.326 0)
			(layer "F.Fab")
			(hide yes)
			(effects
				(font
					(size 1 1)
					(thickness 0.15)
				)
			)
		)
		(property "License" "Apache-2.0"
			(at 181.61 -68.326 0)
			(layer "F.Fab")
			(hide yes)
			(effects
				(font
					(size 1 1)
					(thickness 0.15)
				)
			)
		)
		(property "MPN" "1210POC-682"
			(at 181.61 -68.326 0)
			(layer "F.Fab")
			(hide yes)
			(effects
				(font
					(size 1 1)
					(thickness 0.15)
				)
			)
		)
		(property "Manufacturer" "Coilcraft"
			(at 181.61 -68.326 0)
			(layer "F.Fab")
			(hide yes)
			(effects
				(font
					(size 1 1)
					(thickness 0.15)
				)
			)
		)
		(property "Size" "2.67x3.3"
			(at 181.61 -68.326 0)
			(layer "F.Fab")
			(hide yes)
			(effects
				(font
					(size 1 1)
					(thickness 0.15)
				)
			)
		)
		(property "Val" "6u8/1A"
			(at 181.61 -68.326 0)
			(layer "F.Fab")
			(hide yes)
			(effects
				(font
					(size 1 1)
					(thickness 0.15)
				)
			)
		)
		(sheetname "/Power/")
		(sheetfile "power.kicad_sch")
		(attr smd)
		(fp_line
			(start -0.7 -1.4)
			(end 0.7 -1.4)
			(stroke
				(width 0.15)
				(type solid)
			)
			(layer "F.SilkS")
		)
		(fp_line
			(start -0.7 1.4)
			(end 0.7 1.4)
			(stroke
				(width 0.15)
				(type solid)
			)
			(layer "F.SilkS")
		)
		(fp_rect
			(start -1.9 -1.585)
			(end 1.9 1.585)
			(stroke
				(width 0.05)
				(type solid)
			)
			(fill no)
			(layer "F.CrtYd")
		)
		(fp_line
			(start 1.65 -1.335)
			(end -1.65 -1.335)
			(stroke
				(width 0.15)
				(type solid)
			)
			(layer "F.Fab")
		)
		(fp_line
			(start 1.65 1.335)
			(end 1.65 -1.335)
			(stroke
				(width 0.15)
				(type solid)
			)
			(layer "F.Fab")
		)
		(fp_line
			(start 1.65 1.335)
			(end -1.65 1.335)
			(stroke
				(width 0.15)
				(type solid)
			)
			(layer "F.Fab")
		)
		(fp_line
			(start -1.65 1.335)
			(end -1.65 -1.335)
			(stroke
				(width 0.15)
				(type solid)
			)
			(layer "F.Fab")
		)
		(pad "1" smd rect
			(at -1.27 0 90)
			(size 0.65 2.65)
			(layers "F.Cu" "F.Mask" "F.Paste")
			(net 51 "Net-(L1-Pad2)")
			(pintype "passive")
		)
		(pad "2" smd rect
			(at 1.27 0 90)
			(size 0.65 2.65)
			(layers "F.Cu" "F.Mask" "F.Paste")
			(net 55 "Net-(L5-Pad2)")
			(pintype "passive")
		)
	)
	(footprint "antmicro-footprints:C_0402_1005Metric"
		(layer "F.Cu")
		(at 188.649 53.3088 -90)
		(descr "Capacitor SMD 0402")
		(tags "capacitor SMD 0402")
		(property "Reference" "C23"
			(at -1.086714 -1.359362 90)
			(layer "F.SilkS")
			(effects
				(font
					(size 0.7 0.7)
					(thickness 0.15)
				)
				(justify right bottom)
			)
		)
		(property "Value" "C_100n_0402"
			(at -1.022927 2.155213 90)
			(layer "F.Fab")
			(effects
				(font
					(size 0.7 0.7)
					(thickness 0.15)
				)
				(justify right bottom)
			)
		)
		(property "Datasheet" "https://www.murata.com/products/productdetail?partno=GRM155R61H104KE14%23"
			(at 0 0 270)
			(layer "F.Fab")
			(hide yes)
			(effects
				(font
					(size 1.27 1.27)
					(thickness 0.15)
				)
			)
		)
		(property "Description" "SMD Multilayer Ceramic Capacitor, 0.1 µF, 50 V, 0402 [1005 Metric], ± 10%, X5R, GRM Series"
			(at 0 0 270)
			(layer "F.Fab")
			(hide yes)
			(effects
				(font
					(size 1.27 1.27)
					(thickness 0.15)
				)
			)
		)
		(property "Author" "Antmicro"
			(at 135.3402 241.9578 0)
			(layer "F.Fab")
			(hide yes)
			(effects
				(font
					(size 1 1)
					(thickness 0.15)
				)
			)
		)
		(property "Dielectric" "X5R"
			(at 135.3402 241.9578 0)
			(layer "F.Fab")
			(hide yes)
			(effects
				(font
					(size 1 1)
					(thickness 0.15)
				)
			)
		)
		(property "License" "Apache-2.0"
			(at 135.3402 241.9578 0)
			(layer "F.Fab")
			(hide yes)
			(effects
				(font
					(size 1 1)
					(thickness 0.15)
				)
			)
		)
		(property "MPN" "GRM155R61H104KE14D"
			(at 135.3402 241.9578 0)
			(layer "F.Fab")
			(hide yes)
			(effects
				(font
					(size 1 1)
					(thickness 0.15)
				)
			)
		)
		(property "Manufacturer" "Murata"
			(at 135.3402 241.9578 0)
			(layer "F.Fab")
			(hide yes)
			(effects
				(font
					(size 1 1)
					(thickness 0.15)
				)
			)
		)
		(property "Val" "100n"
			(at 135.3402 241.9578 0)
			(layer "F.Fab")
			(hide yes)
			(effects
				(font
					(size 1 1)
					(thickness 0.15)
				)
			)
		)
		(property "Voltage" "50V"
			(at 135.3402 241.9578 0)
			(layer "F.Fab")
			(hide yes)
			(effects
				(font
					(size 1 1)
					(thickness 0.15)
				)
			)
		)
		(sheetname "/Power/")
		(sheetfile "power.kicad_sch")
		(attr smd)
		(fp_rect
			(start -0.925 -0.47)
			(end 0.925 0.47)
			(stroke
				(width 0.05)
				(type default)
			)
			(fill no)
			(layer "F.CrtYd")
		)
		(fp_line
			(start -0.494 0.248)
			(end -0.494 -0.25)
			(stroke
				(width 0.15)
				(type solid)
			)
			(layer "F.Fab")
		)
		(fp_line
			(start 0.504 0.248)
			(end -0.494 0.248)
			(stroke
				(width 0.15)
				(type solid)
			)
			(layer "F.Fab")
		)
		(fp_line
			(start -0.494 -0.25)
			(end 0.504 -0.25)
			(stroke
				(width 0.15)
				(type solid)
			)
			(layer "F.Fab")
		)
		(fp_line
			(start 0.504 -0.25)
			(end 0.504 0.248)
			(stroke
				(width 0.15)
				(type solid)
			)
			(layer "F.Fab")
		)
		(pad "1" smd roundrect
			(at -0.48 0 270)
			(size 0.59 0.64)
			(layers "F.Cu" "F.Mask" "F.Paste")
			(roundrect_rratio 0.25)
			(net 1 "GND")
			(pintype "passive")
		)
		(pad "2" smd roundrect
			(at 0.48 0 270)
			(size 0.59 0.64)
			(layers "F.Cu" "F.Mask" "F.Paste")
			(roundrect_rratio 0.25)
			(net 113 "/Connectors/FFC_5V")
			(pintype "passive")
		)
	)
	(footprint "antmicro-footprints:R_0603_1608Metric"
		(layer "F.Cu")
		(at 172.05 56.95 -90)
		(descr "Resistor SMD 0603")
		(tags "resistor SMD 0603")
		(property "Reference" "R18"
			(at -1.454542 0.649954 90)
			(layer "F.SilkS")
			(effects
				(font
					(size 0.7 0.7)
					(thickness 0.15)
				)
				(justify right bottom)
			)
		)
		(property "Value" "R_0R_22.4A_0603"
			(at 0 1.6 90)
			(layer "F.Fab")
			(effects
				(font
					(size 0.7 0.7)
					(thickness 0.15)
				)
				(justify right bottom)
			)
		)
		(property "Datasheet" "https://fscdn.rohm.com/en/products/databook/datasheet/passive/resistor/chip_resistor/pmr-jpw-e.pdf"
			(at 0 0 270)
			(layer "F.Fab")
			(hide yes)
			(effects
				(font
					(size 1.27 1.27)
					(thickness 0.15)
				)
			)
		)
		(property "Description" "SMD Chip Resistor"
			(at 0 0 270)
			(layer "F.Fab")
			(hide yes)
			(effects
				(font
					(size 1.27 1.27)
					(thickness 0.15)
				)
			)
		)
		(property "Author" "Antmicro"
			(at 115.1 229 0)
			(layer "F.Fab")
			(hide yes)
			(effects
				(font
					(size 1 1)
					(thickness 0.15)
				)
			)
		)
		(property "License" "Apache-2.0"
			(at 115.1 229 0)
			(layer "F.Fab")
			(hide yes)
			(effects
				(font
					(size 1 1)
					(thickness 0.15)
				)
			)
		)
		(property "MPN" "PMR03EZPJ000"
			(at 115.1 229 0)
			(layer "F.Fab")
			(hide yes)
			(effects
				(font
					(size 1 1)
					(thickness 0.15)
				)
			)
		)
		(property "Manufacturer" "ROHM Semiconductor"
			(at 115.1 229 0)
			(layer "F.Fab")
			(hide yes)
			(effects
				(font
					(size 1 1)
					(thickness 0.15)
				)
			)
		)
		(property "Max. Curr." "22.4A"
			(at 115.1 229 0)
			(layer "F.Fab")
			(hide yes)
			(effects
				(font
					(size 1 1)
					(thickness 0.15)
				)
			)
		)
		(property "Tolerance" "template_tolerance"
			(at 115.1 229 0)
			(layer "F.Fab")
			(hide yes)
			(effects
				(font
					(size 1 1)
					(thickness 0.15)
				)
			)
		)
		(property "Val" "0R"
			(at 115.1 229 0)
			(layer "F.Fab")
			(hide yes)
			(effects
				(font
					(size 1 1)
					(thickness 0.15)
				)
			)
		)
		(sheetname "/Power/")
		(sheetfile "power.kicad_sch")
		(attr smd exclude_from_pos_files exclude_from_bom dnp)
		(fp_line
			(start -0.15 0.4)
			(end 0.15 0.4)
			(stroke
				(width 0.15)
				(type solid)
			)
			(layer "F.SilkS")
		)
		(fp_line
			(start -0.15 -0.4)
			(end 0.15 -0.4)
			(stroke
				(width 0.15)
				(type solid)
			)
			(layer "F.SilkS")
		)
		(fp_rect
			(start -1.25 -0.65)
			(end 1.25 0.65)
			(stroke
				(width 0.05)
				(type solid)
			)
			(fill no)
			(layer "F.CrtYd")
		)
		(fp_rect
			(start -0.8 -0.4)
			(end 0.8 0.4)
			(stroke
				(width 0.15)
				(type solid)
			)
			(fill no)
			(layer "F.Fab")
		)
		(pad "1" smd roundrect
			(at -0.7 0 270)
			(size 0.8 1)
			(layers "F.Cu" "F.Mask" "F.Paste")
			(roundrect_rratio 0.2)
			(net 118 "/Connectors/DC_IN")
			(pintype "passive")
		)
		(pad "2" smd roundrect
			(at 0.7 0 270)
			(size 0.8 1)
			(layers "F.Cu" "F.Mask" "F.Paste")
			(roundrect_rratio 0.2)
			(net 4 "+12V")
			(pintype "passive")
		)
	)
	(footprint "antmicro-footprints:C_0603_1608Metric"
		(layer "F.Cu")
		(at 188.976 50.8 90)
		(descr "Capacitor SMD 0603")
		(tags "capacitor 0603")
		(property "Reference" "C60"
			(at 1.27 0.254 90)
			(layer "F.SilkS")
			(effects
				(font
					(size 0.7 0.7)
					(thickness 0.15)
				)
				(justify left bottom)
			)
		)
		(property "Value" "C_10u_25V_0603"
			(at -1.42757 1.770288 90)
			(layer "F.Fab")
			(effects
				(font
					(size 0.7 0.7)
					(thickness 0.15)
				)
				(justify left bottom)
			)
		)
		(property "Datasheet" "https://product.tdk.com/en/search/capacitor/ceramic/mlcc/info?part_no=C1608X5R1E106M080AC"
			(at 0 0 90)
			(layer "F.Fab")
			(hide yes)
			(effects
				(font
					(size 1.27 1.27)
					(thickness 0.15)
				)
			)
		)
		(property "Description" "SMD Multilayer Ceramic Capacitor, 10 µF, 25 V, 0603 [1608 Metric], ± 20%, X5R, C"
			(at 0 0 90)
			(layer "F.Fab")
			(hide yes)
			(effects
				(font
					(size 1.27 1.27)
					(thickness 0.15)
				)
			)
		)
		(property "Author" "Antmicro"
			(at 239.776 -138.176 0)
			(layer "F.Fab")
			(hide yes)
			(effects
				(font
					(size 1 1)
					(thickness 0.15)
				)
			)
		)
		(property "Dielectric" ""
			(at 239.776 -138.176 0)
			(layer "F.Fab")
			(hide yes)
			(effects
				(font
					(size 1 1)
					(thickness 0.15)
				)
			)
		)
		(property "License" "Apache-2.0"
			(at 239.776 -138.176 0)
			(layer "F.Fab")
			(hide yes)
			(effects
				(font
					(size 1 1)
					(thickness 0.15)
				)
			)
		)
		(property "MPN" "C1608X5R1E106M080AC"
			(at 239.776 -138.176 0)
			(layer "F.Fab")
			(hide yes)
			(effects
				(font
					(size 1 1)
					(thickness 0.15)
				)
			)
		)
		(property "Manufacturer" "TDK"
			(at 239.776 -138.176 0)
			(layer "F.Fab")
			(hide yes)
			(effects
				(font
					(size 1 1)
					(thickness 0.15)
				)
			)
		)
		(property "Val" "10u"
			(at 239.776 -138.176 0)
			(layer "F.Fab")
			(hide yes)
			(effects
				(font
					(size 1 1)
					(thickness 0.15)
				)
			)
		)
		(property "Voltage" "25V"
			(at 239.776 -138.176 0)
			(layer "F.Fab")
			(hide yes)
			(effects
				(font
					(size 1 1)
					(thickness 0.15)
				)
			)
		)
		(sheetname "/Power/")
		(sheetfile "power.kicad_sch")
		(attr smd)
		(fp_line
			(start -0.15 -0.4)
			(end 0.15 -0.4)
			(stroke
				(width 0.15)
				(type solid)
			)
			(layer "F.SilkS")
		)
		(fp_line
			(start -0.15 0.4)
			(end 0.15 0.4)
			(stroke
				(width 0.15)
				(type solid)
			)
			(layer "F.SilkS")
		)
		(fp_rect
			(start -1.25 -0.65)
			(end 1.25 0.65)
			(stroke
				(width 0.05)
				(type solid)
			)
			(fill no)
			(layer "F.CrtYd")
		)
		(fp_rect
			(start -0.8 -0.4)
			(end 0.8 0.4)
			(stroke
				(width 0.15)
				(type solid)
			)
			(fill no)
			(layer "F.Fab")
		)
		(pad "1" smd roundrect
			(at -0.7 0 90)
			(size 0.8 1)
			(layers "F.Cu" "F.Mask" "F.Paste")
			(roundrect_rratio 0.2)
			(net 1 "GND")
			(pintype "passive")
		)
		(pad "2" smd roundrect
			(at 0.7 0 90)
			(size 0.8 1)
			(layers "F.Cu" "F.Mask" "F.Paste")
			(roundrect_rratio 0.2)
			(net 5 "+5V")
			(pintype "passive")
		)
	)
	(footprint "antmicro-footprints:R_0402_1005Metric"
		(layer "F.Cu")
		(at 181.356 65.024)
		(descr "Resistor SMD 0402")
		(tags "resistor SMD 0402")
		(property "Reference" "R12"
			(at -1.247 9.2202 0)
			(layer "F.SilkS")
			(effects
				(font
					(size 0.7 0.7)
					(thickness 0.15)
				)
				(justify left bottom)
			)
		)
		(property "Value" "R_100R_0402"
			(at -1.011843 1.772047 0)
			(layer "F.Fab")
			(effects
				(font
					(size 0.7 0.7)
					(thickness 0.15)
				)
				(justify left bottom)
			)
		)
		(property "Datasheet" "https://www.bourns.com/docs/product-datasheets/cr.pdf"
			(at 0 0 0)
			(layer "F.Fab")
			(hide yes)
			(effects
				(font
					(size 1.27 1.27)
					(thickness 0.15)
				)
			)
		)
		(property "Description" "SMD Chip Resistor, 100 ohm, ± 1%, 62.5 mW, 0402 [1005 Metric], Thick Film, General Purpose"
			(at 0 0 0)
			(layer "F.Fab")
			(hide yes)
			(effects
				(font
					(size 1.27 1.27)
					(thickness 0.15)
				)
			)
		)
		(property "Author" "Antmicro"
			(at 0 0 0)
			(layer "F.Fab")
			(hide yes)
			(effects
				(font
					(size 1 1)
					(thickness 0.15)
				)
			)
		)
		(property "License" "Apache-2.0"
			(at 0 0 0)
			(layer "F.Fab")
			(hide yes)
			(effects
				(font
					(size 1 1)
					(thickness 0.15)
				)
			)
		)
		(property "MPN" "CR0402-FX-1000GLF"
			(at 0 0 0)
			(layer "F.Fab")
			(hide yes)
			(effects
				(font
					(size 1 1)
					(thickness 0.15)
				)
			)
		)
		(property "Manufacturer" "Bourns"
			(at 0 0 0)
			(layer "F.Fab")
			(hide yes)
			(effects
				(font
					(size 1 1)
					(thickness 0.15)
				)
			)
		)
		(property "Tolerance" "1%"
			(at 0 0 0)
			(layer "F.Fab")
			(hide yes)
			(effects
				(font
					(size 1 1)
					(thickness 0.15)
				)
			)
		)
		(property "Val" "100R"
			(at 0 0 0)
			(layer "F.Fab")
			(hide yes)
			(effects
				(font
					(size 1 1)
					(thickness 0.15)
				)
			)
		)
		(sheetname "/Connectors/")
		(sheetfile "connectors.kicad_sch")
		(attr smd)
		(fp_rect
			(start -0.925 -0.47)
			(end 0.925 0.47)
			(stroke
				(width 0.05)
				(type default)
			)
			(fill no)
			(layer "F.CrtYd")
		)
		(fp_rect
			(start -0.5 -0.25)
			(end 0.5 0.25)
			(stroke
				(width 0.15)
				(type solid)
			)
			(fill no)
			(layer "F.Fab")
		)
		(pad "1" smd roundrect
			(at -0.48 0)
			(size 0.59 0.64)
			(layers "F.Cu" "F.Mask" "F.Paste")
			(roundrect_rratio 0.25)
			(net 44 "/Connectors/SDA_CAM")
			(pintype "passive")
		)
		(pad "2" smd roundrect
			(at 0.48 0)
			(size 0.59 0.64)
			(layers "F.Cu" "F.Mask" "F.Paste")
			(roundrect_rratio 0.25)
			(net 42 "/Connectors/SDA_CAM1")
			(pintype "passive")
		)
	)
)
